# T6G (Grand Teton) — schematic netlist excerpt (pin names and nets, part order shuffled) for the footprints in the layout excerpt that follows; sources: Cadence DE-HDL packaged netlist, KiCad conversion of 04192023_DAF0TMB3IC0_F0TG_MB_C_brd_V02_OCP.brd

R3861  Q_RES  0 5% CHIP  pkg 0402LF  page 257 : A = P12V_OCP_V3_2_ISENSE_MAM_TIC ; B = P12V_OCP_V3_2_ISENSE_TIC
R482  Q_RES  0 5% CHIP  pkg 0402LF  page 188 : A = PWRGD_P5V_R ; B = PWRGD_P5V_R1
C7006  Q_CAP  47UF 4V 20% X6S  pkg C0805  page 345 : A = P0V9_CPU1_RT_2D ; B = GND

(kicad_pcb
	(version 20260206)
	(generator "pcbnew")
	(generator_version "10.0")
	(general
		(thickness 1.6)
		(legacy_teardrops no)
	)
	(paper "A4")
	(title_block
		(title "04192023_DAF0TMB3IC0_F0TG_MB_C_brd_V02_OCP.brd")
		(comment 1 "Grand Teton / footprints 1844-1846 of 8354")
	)
	(layers
		(0 "F.Cu" signal "TOP")
		(4 "In1.Cu" signal "GND")
		(6 "In2.Cu" signal "IN1")
		(8 "In3.Cu" signal "GND1")
		(10 "In4.Cu" signal "IN2")
		(12 "In5.Cu" signal "GND2")
		(14 "In6.Cu" signal "IN3")
		(16 "In7.Cu" signal "GND3")
		(18 "In8.Cu" signal "VCC")
		(20 "In9.Cu" signal "VCC1")
		(22 "In10.Cu" signal "GND4")
		(24 "In11.Cu" signal "IN4")
		(26 "In12.Cu" signal "GND5")
		(28 "In13.Cu" signal "IN5")
		(30 "In14.Cu" signal "GND6")
		(32 "In15.Cu" signal "IN6")
		(34 "In16.Cu" signal "GND7")
		(2 "B.Cu" signal "BOTTOM")
		(9 "F.Adhes" user "F.Adhesive")
		(11 "B.Adhes" user "B.Adhesive")
		(13 "F.Paste" user "Package Geometry/Pastemask Top")
		(15 "B.Paste" user "Package Geometry/Pastemask Bottom")
		(5 "F.SilkS" user "Ref Des/Silkscreen Top")
		(7 "B.SilkS" user "Ref Des/Silkscreen Bottom")
		(1 "F.Mask" user "Board Geometry/Soldermask Top")
		(3 "B.Mask" user "Board Geometry/Soldermask Bottom")
		(17 "Dwgs.User" user "User.Drawings")
		(19 "Cmts.User" user "User.Comments")
		(21 "Eco1.User" user "User.Eco1")
		(23 "Eco2.User" user "User.Eco2")
		(25 "Edge.Cuts" user "Board Geometry/Outline")
		(27 "Margin" user)
		(31 "F.CrtYd" user "Package Geometry/Place Bound Top")
		(29 "B.CrtYd" user "Package Geometry/Place Bound Bottom")
		(35 "F.Fab" user "Ref Des/Assembly Top")
		(33 "B.Fab" user "Ref Des/Assembly Bottom")
	)
	(footprint ""
		(layer "F.Cu")
		(at 164.719 -131.953 180)
		(property "Reference" "R482"
			(at 0 0 180)
			(layer "F.SilkS")
			(hide yes)
			(effects
				(font
					(size 1.27 1.27)
				)
			)
		)
		(property "Value" ""
			(at 0 0 180)
			(layer "F.Fab")
			(effects
				(font
					(size 1.27 1.27)
				)
			)
		)
		(duplicate_pad_numbers_are_jumpers no)
		(fp_line
			(start 0.7874 0.4064)
			(end -0.7874 0.4064)
			(stroke
				(width 0.1524)
				(type default)
			)
			(layer "F.SilkS")
		)
		(fp_line
			(start 0.7874 -0.4064)
			(end 0.7874 0.4064)
			(stroke
				(width 0.1524)
				(type default)
			)
			(layer "F.SilkS")
		)
		(fp_line
			(start -0.7874 0.4064)
			(end -0.7874 -0.4064)
			(stroke
				(width 0.1524)
				(type default)
			)
			(layer "F.SilkS")
		)
		(fp_line
			(start -0.7874 -0.4064)
			(end 0.7874 -0.4064)
			(stroke
				(width 0.1524)
				(type default)
			)
			(layer "F.SilkS")
		)
		(fp_line
			(start 0.67945 0.3048)
			(end 0.120396 0.3048)
			(stroke
				(width 0.1)
				(type default)
			)
			(layer "F.Fab")
		)
		(fp_line
			(start 0.67945 -0.3048)
			(end 0.67945 0.3048)
			(stroke
				(width 0.1)
				(type default)
			)
			(layer "F.Fab")
		)
		(fp_line
			(start 0.12065 -0.2794)
			(end 0.12065 -0.3048)
			(stroke
				(width 0.1)
				(type default)
			)
			(layer "F.Fab")
		)
		(fp_line
			(start 0.12065 -0.3048)
			(end 0.67945 -0.3048)
			(stroke
				(width 0.1)
				(type default)
			)
			(layer "F.Fab")
		)
		(fp_line
			(start 0.120396 0.3048)
			(end 0.120396 0.2794)
			(stroke
				(width 0.1)
				(type default)
			)
			(layer "F.Fab")
		)
		(fp_line
			(start 0.120396 0.2794)
			(end -0.12065 0.2794)
			(stroke
				(width 0.1)
				(type default)
			)
			(layer "F.Fab")
		)
		(fp_line
			(start -0.12065 0.3048)
			(end -0.67945 0.3048)
			(stroke
				(width 0.1)
				(type default)
			)
			(layer "F.Fab")
		)
		(fp_line
			(start -0.12065 0.2794)
			(end -0.12065 0.3048)
			(stroke
				(width 0.1)
				(type default)
			)
			(layer "F.Fab")
		)
		(fp_line
			(start -0.12065 -0.2794)
			(end 0.12065 -0.2794)
			(stroke
				(width 0.1)
				(type default)
			)
			(layer "F.Fab")
		)
		(fp_line
			(start -0.12065 -0.305054)
			(end -0.12065 -0.2794)
			(stroke
				(width 0.1)
				(type default)
			)
			(layer "F.Fab")
		)
		(fp_line
			(start -0.67945 0.3048)
			(end -0.67945 -0.305054)
			(stroke
				(width 0.1)
				(type default)
			)
			(layer "F.Fab")
		)
		(fp_line
			(start -0.67945 -0.305054)
			(end -0.12065 -0.305054)
			(stroke
				(width 0.1)
				(type default)
			)
			(layer "F.Fab")
		)
		(pad "1" smd circle
			(at -0.40005 0 180)
			(size 0 0)
			(layers "F.Cu" "F.Mask" "F.Paste")
			(net "PWRGD_P5V_R")
		)
		(pad "2" smd circle
			(at 0.40005 0 180)
			(size 0 0)
			(layers "F.Cu" "F.Mask" "F.Paste")
			(net "PWRGD_P5V_R1")
		)
	)
	(footprint ""
		(layer "F.Cu")
		(at 322.837048 -44.716954)
		(property "Reference" "R3861"
			(at 0 0 0)
			(layer "F.SilkS")
			(hide yes)
			(effects
				(font
					(size 1.27 1.27)
				)
			)
		)
		(property "Value" ""
			(at 0 0 0)
			(layer "F.Fab")
			(effects
				(font
					(size 1.27 1.27)
				)
			)
		)
		(duplicate_pad_numbers_are_jumpers no)
		(fp_line
			(start -0.7874 -0.4064)
			(end 0.7874 -0.4064)
			(stroke
				(width 0.1524)
				(type default)
			)
			(layer "F.SilkS")
		)
		(fp_line
			(start -0.7874 0.4064)
			(end -0.7874 -0.4064)
			(stroke
				(width 0.1524)
				(type default)
			)
			(layer "F.SilkS")
		)
		(fp_line
			(start 0.7874 -0.4064)
			(end 0.7874 0.4064)
			(stroke
				(width 0.1524)
				(type default)
			)
			(layer "F.SilkS")
		)
		(fp_line
			(start 0.7874 0.4064)
			(end -0.7874 0.4064)
			(stroke
				(width 0.1524)
				(type default)
			)
			(layer "F.SilkS")
		)
		(fp_line
			(start -0.67945 -0.305054)
			(end -0.12065 -0.305054)
			(stroke
				(width 0.1)
				(type default)
			)
			(layer "F.Fab")
		)
		(fp_line
			(start -0.67945 0.3048)
			(end -0.67945 -0.305054)
			(stroke
				(width 0.1)
				(type default)
			)
			(layer "F.Fab")
		)
		(fp_line
			(start -0.12065 -0.305054)
			(end -0.12065 -0.2794)
			(stroke
				(width 0.1)
				(type default)
			)
			(layer "F.Fab")
		)
		(fp_line
			(start -0.12065 -0.2794)
			(end 0.12065 -0.2794)
			(stroke
				(width 0.1)
				(type default)
			)
			(layer "F.Fab")
		)
		(fp_line
			(start -0.12065 0.2794)
			(end -0.12065 0.3048)
			(stroke
				(width 0.1)
				(type default)
			)
			(layer "F.Fab")
		)
		(fp_line
			(start -0.12065 0.3048)
			(end -0.67945 0.3048)
			(stroke
				(width 0.1)
				(type default)
			)
			(layer "F.Fab")
		)
		(fp_line
			(start 0.120396 0.2794)
			(end -0.12065 0.2794)
			(stroke
				(width 0.1)
				(type default)
			)
			(layer "F.Fab")
		)
		(fp_line
			(start 0.120396 0.3048)
			(end 0.120396 0.2794)
			(stroke
				(width 0.1)
				(type default)
			)
			(layer "F.Fab")
		)
		(fp_line
			(start 0.12065 -0.3048)
			(end 0.67945 -0.3048)
			(stroke
				(width 0.1)
				(type default)
			)
			(layer "F.Fab")
		)
		(fp_line
			(start 0.12065 -0.2794)
			(end 0.12065 -0.3048)
			(stroke
				(width 0.1)
				(type default)
			)
			(layer "F.Fab")
		)
		(fp_line
			(start 0.67945 -0.3048)
			(end 0.67945 0.3048)
			(stroke
				(width 0.1)
				(type default)
			)
			(layer "F.Fab")
		)
		(fp_line
			(start 0.67945 0.3048)
			(end 0.120396 0.3048)
			(stroke
				(width 0.1)
				(type default)
			)
			(layer "F.Fab")
		)
		(pad "1" smd rect
			(at -0.40005 0 180)
			(size 0.4572 0.508)
			(layers "F.Cu" "F.Mask" "F.Paste")
			(net "P12V_OCP_V3_2_ISENSE_MAM_TIC")
		)
		(pad "2" smd rect
			(at 0.40005 0 180)
			(size 0.4572 0.508)
			(layers "F.Cu" "F.Mask" "F.Paste")
			(net "P12V_OCP_V3_2_ISENSE_TIC")
		)
	)
	(footprint ""
		(layer "F.Cu")
		(at 140.3096 -401.866608 90)
		(property "Reference" "C7006"
			(at 0 0 90)
			(layer "F.SilkS")
			(hide yes)
			(effects
				(font
					(size 1.27 1.27)
				)
			)
		)
		(property "Value" ""
			(at 0 0 90)
			(layer "F.Fab")
			(effects
				(font
					(size 1.27 1.27)
				)
			)
		)
		(duplicate_pad_numbers_are_jumpers no)
		(fp_line
			(start 1.524 -0.762)
			(end 1.524 0.762)
			(stroke
				(width 0.1524)
				(type default)
			)
			(layer "F.SilkS")
		)
		(fp_line
			(start -1.524 -0.762)
			(end 1.524 -0.762)
			(stroke
				(width 0.1524)
				(type default)
			)
			(layer "F.SilkS")
		)
		(fp_line
			(start 1.524 0.762)
			(end -1.524 0.762)
			(stroke
				(width 0.1524)
				(type default)
			)
			(layer "F.SilkS")
		)
		(fp_line
			(start -1.524 0.762)
			(end -1.524 -0.762)
			(stroke
				(width 0.1524)
				(type default)
			)
			(layer "F.SilkS")
		)
		(fp_line
			(start 1.1049 -0.724916)
			(end -1.1049 -0.724916)
			(stroke
				(width 0.1)
				(type default)
			)
			(layer "F.Fab")
		)
		(fp_line
			(start -1.1049 -0.724916)
			(end -1.1049 0.724916)
			(stroke
				(width 0.1)
				(type default)
			)
			(layer "F.Fab")
		)
		(fp_line
			(start 1.1049 0.724916)
			(end 1.1049 -0.724916)
			(stroke
				(width 0.1)
				(type default)
			)
			(layer "F.Fab")
		)
		(fp_line
			(start -1.1049 0.724916)
			(end 1.1049 0.724916)
			(stroke
				(width 0.1)
				(type default)
			)
			(layer "F.Fab")
		)
		(pad "1" smd rect
			(at -0.889 0 270)
			(size 1.016 1.27)
			(layers "F.Cu" "F.Mask" "F.Paste")
			(net "P0V9_CPU1_RT_2D")
		)
		(pad "2" smd rect
			(at 0.889 0 270)
			(size 1.016 1.27)
			(layers "F.Cu" "F.Mask" "F.Paste")
			(net "GND")
		)
	)
)
